(kicad_pcb
	(version 20260206)
	(generator "pcbnew")
	(generator_version "10.0")
	(general
		(thickness 1.6)
		(legacy_teardrops no)
	)
	(paper "A4")
	(title_block
		(title "01162023_DA0F0TEBIF0_F0T_Expander_BD_F_brd_V02_OCP.brd")
		(comment 1 "Grand Teton / footprints 2850-2856 of 9728")
	)
	(layers
		(0 "F.Cu" signal "TOP")
		(4 "In1.Cu" signal "GND")
		(6 "In2.Cu" signal "VCC")
		(8 "In3.Cu" signal "VCC1")
		(10 "In4.Cu" signal "GND1")
		(12 "In5.Cu" signal "IN1")
		(14 "In6.Cu" signal "GND2")
		(16 "In7.Cu" signal "IN2")
		(18 "In8.Cu" signal "GND3")
		(20 "In9.Cu" signal "IN3")
		(22 "In10.Cu" signal "GND4")
		(24 "In11.Cu" signal "IN4")
		(26 "In12.Cu" signal "GND5")
		(28 "In13.Cu" signal "IN5")
		(30 "In14.Cu" signal "GND6")
		(32 "In15.Cu" signal "IN6")
		(34 "In16.Cu" signal "GND7")
		(2 "B.Cu" signal "BOTTOM")
		(9 "F.Adhes" user "F.Adhesive")
		(11 "B.Adhes" user "B.Adhesive")
		(13 "F.Paste" user "Package Geometry/Pastemask Top")
		(15 "B.Paste" user "Package Geometry/Pastemask Bottom")
		(5 "F.SilkS" user "Ref Des/Silkscreen Top")
		(7 "B.SilkS" user "Ref Des/Silkscreen Bottom")
		(1 "F.Mask" user "Board Geometry/Soldermask Top")
		(3 "B.Mask" user "Board Geometry/Soldermask Bottom")
		(17 "Dwgs.User" user "User.Drawings")
		(19 "Cmts.User" user "User.Comments")
		(21 "Eco1.User" user "User.Eco1")
		(23 "Eco2.User" user "User.Eco2")
		(25 "Edge.Cuts" user "Board Geometry/Outline")
		(27 "Margin" user)
		(31 "F.CrtYd" user "Package Geometry/Place Bound Top")
		(29 "B.CrtYd" user "Package Geometry/Place Bound Bottom")
		(35 "F.Fab" user "Ref Des/Assembly Top")
		(33 "B.Fab" user "Ref Des/Assembly Bottom")
	)
	(footprint ""
		(layer "F.Cu")
		(at 214.274908 -48.753014 180)
		(property "Reference" "C312"
			(at 0 0 180)
			(layer "F.SilkS")
			(hide yes)
			(effects
				(font
					(size 1.27 1.27)
				)
			)
		)
		(property "Value" ""
			(at 0 0 180)
			(layer "F.Fab")
			(effects
				(font
					(size 1.27 1.27)
				)
			)
		)
		(duplicate_pad_numbers_are_jumpers no)
		(fp_line
			(start 0.7874 0.4064)
			(end -0.7874 0.4064)
			(stroke
				(width 0.1524)
				(type default)
			)
			(layer "F.SilkS")
		)
		(fp_line
			(start 0.7874 -0.4064)
			(end 0.7874 0.4064)
			(stroke
				(width 0.1524)
				(type default)
			)
			(layer "F.SilkS")
		)
		(fp_line
			(start -0.7874 0.4064)
			(end -0.7874 -0.4064)
			(stroke
				(width 0.1524)
				(type default)
			)
			(layer "F.SilkS")
		)
		(fp_line
			(start -0.7874 -0.4064)
			(end 0.7874 -0.4064)
			(stroke
				(width 0.1524)
				(type default)
			)
			(layer "F.SilkS")
		)
		(fp_line
			(start 0.67945 0.3048)
			(end 0.120396 0.3048)
			(stroke
				(width 0.1)
				(type default)
			)
			(layer "F.Fab")
		)
		(fp_line
			(start 0.67945 -0.3048)
			(end 0.67945 0.3048)
			(stroke
				(width 0.1)
				(type default)
			)
			(layer "F.Fab")
		)
		(fp_line
			(start 0.12065 -0.2794)
			(end 0.12065 -0.3048)
			(stroke
				(width 0.1)
				(type default)
			)
			(layer "F.Fab")
		)
		(fp_line
			(start 0.12065 -0.3048)
			(end 0.67945 -0.3048)
			(stroke
				(width 0.1)
				(type default)
			)
			(layer "F.Fab")
		)
		(fp_line
			(start 0.120396 0.3048)
			(end 0.120396 0.2794)
			(stroke
				(width 0.1)
				(type default)
			)
			(layer "F.Fab")
		)
		(fp_line
			(start 0.120396 0.2794)
			(end -0.12065 0.2794)
			(stroke
				(width 0.1)
				(type default)
			)
			(layer "F.Fab")
		)
		(fp_line
			(start -0.12065 0.3048)
			(end -0.67945 0.3048)
			(stroke
				(width 0.1)
				(type default)
			)
			(layer "F.Fab")
		)
		(fp_line
			(start -0.12065 0.2794)
			(end -0.12065 0.3048)
			(stroke
				(width 0.1)
				(type default)
			)
			(layer "F.Fab")
		)
		(fp_line
			(start -0.12065 -0.2794)
			(end 0.12065 -0.2794)
			(stroke
				(width 0.1)
				(type default)
			)
			(layer "F.Fab")
		)
		(fp_line
			(start -0.12065 -0.305054)
			(end -0.12065 -0.2794)
			(stroke
				(width 0.1)
				(type default)
			)
			(layer "F.Fab")
		)
		(fp_line
			(start -0.67945 0.3048)
			(end -0.67945 -0.305054)
			(stroke
				(width 0.1)
				(type default)
			)
			(layer "F.Fab")
		)
		(fp_line
			(start -0.67945 -0.305054)
			(end -0.12065 -0.305054)
			(stroke
				(width 0.1)
				(type default)
			)
			(layer "F.Fab")
		)
		(pad "1" smd circle
			(at -0.40005 0 180)
			(size 0 0)
			(layers "F.Cu" "F.Mask" "F.Paste")
			(net "P3V3_AUX")
		)
		(pad "2" smd circle
			(at 0.40005 0 180)
			(size 0 0)
			(layers "F.Cu" "F.Mask" "F.Paste")
			(net "GND")
		)
	)
	(footprint ""
		(layer "F.Cu")
		(at 259.590286 -252.356874 -90)
		(property "Reference" "R1361"
			(at 0 0 270)
			(layer "F.SilkS")
			(hide yes)
			(effects
				(font
					(size 1.27 1.27)
				)
			)
		)
		(property "Value" ""
			(at 0 0 270)
			(layer "F.Fab")
			(effects
				(font
					(size 1.27 1.27)
				)
			)
		)
		(duplicate_pad_numbers_are_jumpers no)
		(fp_line
			(start -0.7874 0.4064)
			(end -0.7874 -0.4064)
			(stroke
				(width 0.1524)
				(type default)
			)
			(layer "F.SilkS")
		)
		(fp_line
			(start 0.7874 0.4064)
			(end -0.7874 0.4064)
			(stroke
				(width 0.1524)
				(type default)
			)
			(layer "F.SilkS")
		)
		(fp_line
			(start -0.7874 -0.4064)
			(end 0.7874 -0.4064)
			(stroke
				(width 0.1524)
				(type default)
			)
			(layer "F.SilkS")
		)
		(fp_line
			(start 0.7874 -0.4064)
			(end 0.7874 0.4064)
			(stroke
				(width 0.1524)
				(type default)
			)
			(layer "F.SilkS")
		)
		(fp_line
			(start -0.67945 0.3048)
			(end -0.67945 -0.305054)
			(stroke
				(width 0.1)
				(type default)
			)
			(layer "F.Fab")
		)
		(fp_line
			(start -0.12065 0.3048)
			(end -0.67945 0.3048)
			(stroke
				(width 0.1)
				(type default)
			)
			(layer "F.Fab")
		)
		(fp_line
			(start 0.120396 0.3048)
			(end 0.120396 0.2794)
			(stroke
				(width 0.1)
				(type default)
			)
			(layer "F.Fab")
		)
		(fp_line
			(start 0.67945 0.3048)
			(end 0.120396 0.3048)
			(stroke
				(width 0.1)
				(type default)
			)
			(layer "F.Fab")
		)
		(fp_line
			(start -0.12065 0.2794)
			(end -0.12065 0.3048)
			(stroke
				(width 0.1)
				(type default)
			)
			(layer "F.Fab")
		)
		(fp_line
			(start 0.120396 0.2794)
			(end -0.12065 0.2794)
			(stroke
				(width 0.1)
				(type default)
			)
			(layer "F.Fab")
		)
		(fp_line
			(start -0.12065 -0.2794)
			(end 0.12065 -0.2794)
			(stroke
				(width 0.1)
				(type default)
			)
			(layer "F.Fab")
		)
		(fp_line
			(start 0.12065 -0.2794)
			(end 0.12065 -0.3048)
			(stroke
				(width 0.1)
				(type default)
			)
			(layer "F.Fab")
		)
		(fp_line
			(start 0.12065 -0.3048)
			(end 0.67945 -0.3048)
			(stroke
				(width 0.1)
				(type default)
			)
			(layer "F.Fab")
		)
		(fp_line
			(start 0.67945 -0.3048)
			(end 0.67945 0.3048)
			(stroke
				(width 0.1)
				(type default)
			)
			(layer "F.Fab")
		)
		(fp_line
			(start -0.67945 -0.305054)
			(end -0.12065 -0.305054)
			(stroke
				(width 0.1)
				(type default)
			)
			(layer "F.Fab")
		)
		(fp_line
			(start -0.12065 -0.305054)
			(end -0.12065 -0.2794)
			(stroke
				(width 0.1)
				(type default)
			)
			(layer "F.Fab")
		)
		(pad "1" smd circle
			(at -0.40005 0 270)
			(size 0 0)
			(layers "F.Cu" "F.Mask" "F.Paste")
			(net "GND")
		)
		(pad "2" smd circle
			(at 0.40005 0 270)
			(size 0 0)
			(layers "F.Cu" "F.Mask" "F.Paste")
			(net "PEX2_MODE_SEL5")
		)
	)
	(footprint ""
		(layer "F.Cu")
		(at 145.522442 -250.070874 -90)
		(property "Reference" "R1272"
			(at 0 0 270)
			(layer "F.SilkS")
			(hide yes)
			(effects
				(font
					(size 1.27 1.27)
				)
			)
		)
		(property "Value" ""
			(at 0 0 270)
			(layer "F.Fab")
			(effects
				(font
					(size 1.27 1.27)
				)
			)
		)
		(duplicate_pad_numbers_are_jumpers no)
		(fp_line
			(start -0.7874 0.4064)
			(end -0.7874 -0.4064)
			(stroke
				(width 0.1524)
				(type default)
			)
			(layer "F.SilkS")
		)
		(fp_line
			(start 0.7874 0.4064)
			(end -0.7874 0.4064)
			(stroke
				(width 0.1524)
				(type default)
			)
			(layer "F.SilkS")
		)
		(fp_line
			(start -0.7874 -0.4064)
			(end 0.7874 -0.4064)
			(stroke
				(width 0.1524)
				(type default)
			)
			(layer "F.SilkS")
		)
		(fp_line
			(start 0.7874 -0.4064)
			(end 0.7874 0.4064)
			(stroke
				(width 0.1524)
				(type default)
			)
			(layer "F.SilkS")
		)
		(fp_line
			(start -0.67945 0.3048)
			(end -0.67945 -0.305054)
			(stroke
				(width 0.1)
				(type default)
			)
			(layer "F.Fab")
		)
		(fp_line
			(start -0.12065 0.3048)
			(end -0.67945 0.3048)
			(stroke
				(width 0.1)
				(type default)
			)
			(layer "F.Fab")
		)
		(fp_line
			(start 0.120396 0.3048)
			(end 0.120396 0.2794)
			(stroke
				(width 0.1)
				(type default)
			)
			(layer "F.Fab")
		)
		(fp_line
			(start 0.67945 0.3048)
			(end 0.120396 0.3048)
			(stroke
				(width 0.1)
				(type default)
			)
			(layer "F.Fab")
		)
		(fp_line
			(start -0.12065 0.2794)
			(end -0.12065 0.3048)
			(stroke
				(width 0.1)
				(type default)
			)
			(layer "F.Fab")
		)
		(fp_line
			(start 0.120396 0.2794)
			(end -0.12065 0.2794)
			(stroke
				(width 0.1)
				(type default)
			)
			(layer "F.Fab")
		)
		(fp_line
			(start -0.12065 -0.2794)
			(end 0.12065 -0.2794)
			(stroke
				(width 0.1)
				(type default)
			)
			(layer "F.Fab")
		)
		(fp_line
			(start 0.12065 -0.2794)
			(end 0.12065 -0.3048)
			(stroke
				(width 0.1)
				(type default)
			)
			(layer "F.Fab")
		)
		(fp_line
			(start 0.12065 -0.3048)
			(end 0.67945 -0.3048)
			(stroke
				(width 0.1)
				(type default)
			)
			(layer "F.Fab")
		)
		(fp_line
			(start 0.67945 -0.3048)
			(end 0.67945 0.3048)
			(stroke
				(width 0.1)
				(type default)
			)
			(layer "F.Fab")
		)
		(fp_line
			(start -0.67945 -0.305054)
			(end -0.12065 -0.305054)
			(stroke
				(width 0.1)
				(type default)
			)
			(layer "F.Fab")
		)
		(fp_line
			(start -0.12065 -0.305054)
			(end -0.12065 -0.2794)
			(stroke
				(width 0.1)
				(type default)
			)
			(layer "F.Fab")
		)
		(pad "1" smd circle
			(at -0.40005 0 270)
			(size 0 0)
			(layers "F.Cu" "F.Mask" "F.Paste")
			(net "PEX1_MODE_SEL3")
		)
		(pad "2" smd circle
			(at 0.40005 0 270)
			(size 0 0)
			(layers "F.Cu" "F.Mask" "F.Paste")
			(net "P1V8_PEX")
		)
	)
	(footprint ""
		(layer "F.Cu")
		(at 25.222708 -237.733586)
		(property "Reference" "ME6"
			(at 0 0 0)
			(layer "F.SilkS")
			(hide yes)
			(effects
				(font
					(size 1.27 1.27)
				)
			)
		)
		(property "Value" ""
			(at 0 0 0)
			(layer "F.Fab")
			(effects
				(font
					(size 1.27 1.27)
				)
			)
		)
		(duplicate_pad_numbers_are_jumpers no)
	)
	(footprint ""
		(layer "F.Cu")
		(at 132.459476 -146.642328 -90)
		(property "Reference" "C888"
			(at 0 0 270)
			(layer "F.SilkS")
			(hide yes)
			(effects
				(font
					(size 1.27 1.27)
				)
			)
		)
		(property "Value" ""
			(at 0 0 270)
			(layer "F.Fab")
			(effects
				(font
					(size 1.27 1.27)
				)
			)
		)
		(duplicate_pad_numbers_are_jumpers no)
		(fp_line
			(start -0.7874 0.4064)
			(end -0.7874 -0.4064)
			(stroke
				(width 0.1524)
				(type default)
			)
			(layer "F.SilkS")
		)
		(fp_line
			(start 0.7874 0.4064)
			(end -0.7874 0.4064)
			(stroke
				(width 0.1524)
				(type default)
			)
			(layer "F.SilkS")
		)
		(fp_line
			(start -0.7874 -0.4064)
			(end 0.7874 -0.4064)
			(stroke
				(width 0.1524)
				(type default)
			)
			(layer "F.SilkS")
		)
		(fp_line
			(start 0.7874 -0.4064)
			(end 0.7874 0.4064)
			(stroke
				(width 0.1524)
				(type default)
			)
			(layer "F.SilkS")
		)
		(fp_line
			(start -0.67945 0.3048)
			(end -0.67945 -0.305054)
			(stroke
				(width 0.1)
				(type default)
			)
			(layer "F.Fab")
		)
		(fp_line
			(start -0.12065 0.3048)
			(end -0.67945 0.3048)
			(stroke
				(width 0.1)
				(type default)
			)
			(layer "F.Fab")
		)
		(fp_line
			(start 0.120396 0.3048)
			(end 0.120396 0.2794)
			(stroke
				(width 0.1)
				(type default)
			)
			(layer "F.Fab")
		)
		(fp_line
			(start 0.67945 0.3048)
			(end 0.120396 0.3048)
			(stroke
				(width 0.1)
				(type default)
			)
			(layer "F.Fab")
		)
		(fp_line
			(start -0.12065 0.2794)
			(end -0.12065 0.3048)
			(stroke
				(width 0.1)
				(type default)
			)
			(layer "F.Fab")
		)
		(fp_line
			(start 0.120396 0.2794)
			(end -0.12065 0.2794)
			(stroke
				(width 0.1)
				(type default)
			)
			(layer "F.Fab")
		)
		(fp_line
			(start -0.12065 -0.2794)
			(end 0.12065 -0.2794)
			(stroke
				(width 0.1)
				(type default)
			)
			(layer "F.Fab")
		)
		(fp_line
			(start 0.12065 -0.2794)
			(end 0.12065 -0.3048)
			(stroke
				(width 0.1)
				(type default)
			)
			(layer "F.Fab")
		)
		(fp_line
			(start 0.12065 -0.3048)
			(end 0.67945 -0.3048)
			(stroke
				(width 0.1)
				(type default)
			)
			(layer "F.Fab")
		)
		(fp_line
			(start 0.67945 -0.3048)
			(end 0.67945 0.3048)
			(stroke
				(width 0.1)
				(type default)
			)
			(layer "F.Fab")
		)
		(fp_line
			(start -0.67945 -0.305054)
			(end -0.12065 -0.305054)
			(stroke
				(width 0.1)
				(type default)
			)
			(layer "F.Fab")
		)
		(fp_line
			(start -0.12065 -0.305054)
			(end -0.12065 -0.2794)
			(stroke
				(width 0.1)
				(type default)
			)
			(layer "F.Fab")
		)
		(pad "1" smd circle
			(at -0.40005 0 270)
			(size 0 0)
			(layers "F.Cu" "F.Mask" "F.Paste")
			(net "P3V3_AUX")
		)
		(pad "2" smd circle
			(at 0.40005 0 270)
			(size 0 0)
			(layers "F.Cu" "F.Mask" "F.Paste")
			(net "GND")
		)
	)
	(footprint ""
		(layer "F.Cu")
		(at 459.077822 -365.676688 -90)
		(property "Reference" "C4454"
			(at 0 0 270)
			(layer "F.SilkS")
			(hide yes)
			(effects
				(font
					(size 1.27 1.27)
				)
			)
		)
		(property "Value" ""
			(at 0 0 270)
			(layer "F.Fab")
			(effects
				(font
					(size 1.27 1.27)
				)
			)
		)
		(duplicate_pad_numbers_are_jumpers no)
		(fp_line
			(start -0.299974 0.150114)
			(end -0.299974 -0.150114)
			(stroke
				(width 0.1)
				(type default)
			)
			(layer "F.Fab")
		)
		(fp_line
			(start 0.299974 0.150114)
			(end -0.299974 0.150114)
			(stroke
				(width 0.1)
				(type default)
			)
			(layer "F.Fab")
		)
		(fp_line
			(start -0.299974 -0.150114)
			(end 0.299974 -0.150114)
			(stroke
				(width 0.1)
				(type default)
			)
			(layer "F.Fab")
		)
		(fp_line
			(start 0.299974 -0.150114)
			(end 0.299974 0.150114)
			(stroke
				(width 0.1)
				(type default)
			)
			(layer "F.Fab")
		)
		(pad "1" smd rect
			(at -0.2667 0 270)
			(size 0.3048 0.381)
			(layers "F.Cu" "F.Mask" "F.Paste")
			(net "GPU_3V3IO_RSVD4_ISO")
		)
		(pad "2" smd rect
			(at 0.2667 0 270)
			(size 0.3048 0.381)
			(layers "F.Cu" "F.Mask" "F.Paste")
			(net "GND")
		)
	)
	(footprint ""
		(layer "F.Cu")
		(at 220.559376 -22.955504 90)
		(property "Reference" "R1686"
			(at 0 0 90)
			(layer "F.SilkS")
			(hide yes)
			(effects
				(font
					(size 1.27 1.27)
				)
			)
		)
		(property "Value" ""
			(at 0 0 90)
			(layer "F.Fab")
			(effects
				(font
					(size 1.27 1.27)
				)
			)
		)
		(duplicate_pad_numbers_are_jumpers no)
		(fp_line
			(start 0.7874 -0.4064)
			(end 0.7874 0.4064)
			(stroke
				(width 0.1524)
				(type default)
			)
			(layer "F.SilkS")
		)
		(fp_line
			(start -0.7874 -0.4064)
			(end 0.7874 -0.4064)
			(stroke
				(width 0.1524)
				(type default)
			)
			(layer "F.SilkS")
		)
		(fp_line
			(start 0.7874 0.4064)
			(end -0.7874 0.4064)
			(stroke
				(width 0.1524)
				(type default)
			)
			(layer "F.SilkS")
		)
		(fp_line
			(start -0.7874 0.4064)
			(end -0.7874 -0.4064)
			(stroke
				(width 0.1524)
				(type default)
			)
			(layer "F.SilkS")
		)
		(fp_line
			(start -0.12065 -0.305054)
			(end -0.12065 -0.2794)
			(stroke
				(width 0.1)
				(type default)
			)
			(layer "F.Fab")
		)
		(fp_line
			(start -0.67945 -0.305054)
			(end -0.12065 -0.305054)
			(stroke
				(width 0.1)
				(type default)
			)
			(layer "F.Fab")
		)
		(fp_line
			(start 0.67945 -0.3048)
			(end 0.67945 0.3048)
			(stroke
				(width 0.1)
				(type default)
			)
			(layer "F.Fab")
		)
		(fp_line
			(start 0.12065 -0.3048)
			(end 0.67945 -0.3048)
			(stroke
				(width 0.1)
				(type default)
			)
			(layer "F.Fab")
		)
		(fp_line
			(start 0.12065 -0.2794)
			(end 0.12065 -0.3048)
			(stroke
				(width 0.1)
				(type default)
			)
			(layer "F.Fab")
		)
		(fp_line
			(start -0.12065 -0.2794)
			(end 0.12065 -0.2794)
			(stroke
				(width 0.1)
				(type default)
			)
			(layer "F.Fab")
		)
		(fp_line
			(start 0.120396 0.2794)
			(end -0.12065 0.2794)
			(stroke
				(width 0.1)
				(type default)
			)
			(layer "F.Fab")
		)
		(fp_line
			(start -0.12065 0.2794)
			(end -0.12065 0.3048)
			(stroke
				(width 0.1)
				(type default)
			)
			(layer "F.Fab")
		)
		(fp_line
			(start 0.67945 0.3048)
			(end 0.120396 0.3048)
			(stroke
				(width 0.1)
				(type default)
			)
			(layer "F.Fab")
		)
		(fp_line
			(start 0.120396 0.3048)
			(end 0.120396 0.2794)
			(stroke
				(width 0.1)
				(type default)
			)
			(layer "F.Fab")
		)
		(fp_line
			(start -0.12065 0.3048)
			(end -0.67945 0.3048)
			(stroke
				(width 0.1)
				(type default)
			)
			(layer "F.Fab")
		)
		(fp_line
			(start -0.67945 0.3048)
			(end -0.67945 -0.305054)
			(stroke
				(width 0.1)
				(type default)
			)
			(layer "F.Fab")
		)
		(pad "1" smd circle
			(at -0.40005 0 90)
			(size 0 0)
			(layers "F.Cu" "F.Mask" "F.Paste")
			(net "SMB_BIC_I2C9_MUX0_SSD7_R_SCL")
		)
		(pad "2" smd circle
			(at 0.40005 0 90)
			(size 0 0)
			(layers "F.Cu" "F.Mask" "F.Paste")
			(net "SMB_ISO_SSD7_SCL")
		)
	)
)
